(kicad_pcb
	(version 20260206)
	(generator "pcbnew")
	(generator_version "10.0")
	(general
		(thickness 1.6)
		(legacy_teardrops no)
	)
	(paper "A4")
	(title_block
		(title "Wiwynn_Tioga_Pass_MB.brd")
		(comment 1 "Tioga Pass / footprints 2814-2821 of 4770")
	)
	(layers
		(0 "F.Cu" signal "TOP")
		(4 "In1.Cu" signal "L2GND")
		(6 "In2.Cu" signal "L3")
		(8 "In3.Cu" signal "L4GND")
		(10 "In4.Cu" signal "L5")
		(12 "In5.Cu" signal "L6GND")
		(14 "In6.Cu" signal "L7VCC")
		(16 "In7.Cu" signal "L8VCC")
		(18 "In8.Cu" signal "L9GND")
		(20 "In9.Cu" signal "L10")
		(22 "In10.Cu" signal "L11GND")
		(24 "In11.Cu" signal "L12")
		(26 "In12.Cu" signal "L13GND")
		(2 "B.Cu" signal "BOTTOM")
		(9 "F.Adhes" user "F.Adhesive")
		(11 "B.Adhes" user "B.Adhesive")
		(13 "F.Paste" user "Package Geometry/Pastemask Top")
		(15 "B.Paste" user "Package Geometry/Pastemask Bottom")
		(5 "F.SilkS" user "Ref Des/Silkscreen Top")
		(7 "B.SilkS" user "Ref Des/Silkscreen Bottom")
		(1 "F.Mask" user "Board Geometry/Soldermask Top")
		(3 "B.Mask" user "Board Geometry/Soldermask Bottom")
		(17 "Dwgs.User" user "User.Drawings")
		(19 "Cmts.User" user "User.Comments")
		(21 "Eco1.User" user "User.Eco1")
		(23 "Eco2.User" user "User.Eco2")
		(25 "Edge.Cuts" user "Board Geometry/Outline")
		(27 "Margin" user)
		(31 "F.CrtYd" user "Package Geometry/Place Bound Top")
		(29 "B.CrtYd" user "Package Geometry/Place Bound Bottom")
		(35 "F.Fab" user "Ref Des/Assembly Top")
		(33 "B.Fab" user "Ref Des/Assembly Bottom")
	)
	(footprint ""
		(layer "B.Cu")
		(at 344.522806 -60.368434)
		(property "Reference" "R2U22"
			(at 0 0 0)
			(layer "B.SilkS")
			(hide yes)
			(effects
				(font
					(size 1.27 1.27)
				)
				(justify mirror)
			)
		)
		(property "Value" ""
			(at 0 0 0)
			(layer "B.Fab")
			(effects
				(font
					(size 1.27 1.27)
				)
				(justify mirror)
			)
		)
		(duplicate_pad_numbers_are_jumpers no)
		(fp_poly
			(pts
				(xy 0.2794 -0.1016) (xy -0.2794 -0.1016) (xy -0.2794 0.9906) (xy 0.2794 0.9906)
			)
			(stroke
				(width 0)
				(type default)
			)
			(fill no)
			(layer "B.CrtYd")
		)
		(fp_line
			(start -0.2794 -0.1016)
			(end 0.2794 -0.1016)
			(stroke
				(width 0.1)
				(type default)
			)
			(layer "B.Fab")
		)
		(fp_line
			(start -0.2794 0.9906)
			(end -0.2794 -0.1016)
			(stroke
				(width 0.1)
				(type default)
			)
			(layer "B.Fab")
		)
		(fp_line
			(start 0.2794 -0.1016)
			(end 0.2794 0.9906)
			(stroke
				(width 0.1)
				(type default)
			)
			(layer "B.Fab")
		)
		(fp_line
			(start 0.2794 0.9906)
			(end -0.2794 0.9906)
			(stroke
				(width 0.1)
				(type default)
			)
			(layer "B.Fab")
		)
		(pad "1" smd rect
			(at 0 0 180)
			(size 0.508 0.508)
			(layers "B.Cu" "B.Mask" "B.Paste")
			(net "P3E_CPU0_PE1_SS_RXP<4>")
		)
		(pad "2" smd rect
			(at 0 0.889 180)
			(size 0.508 0.508)
			(layers "B.Cu" "B.Mask" "B.Paste")
			(net "P3E_CPU0_PE1_SS_R_RXP<4>")
		)
		(zone
			(layer "B.Cu")
			(hatch none 0.5)
			(connect_pads
				(clearance 0)
			)
			(min_thickness 0.25)
			(keepout
				(tracks allowed)
				(vias not_allowed)
				(pads allowed)
				(copperpour not_allowed)
				(footprints allowed)
			)
			(placement
				(enabled no)
				(sheetname "")
			)
			(fill
				(thermal_gap 0.5)
				(thermal_bridge_width 0.5)
				(island_removal_mode 0)
			)
			(polygon
				(pts
					(xy 344.776806 -60.114434) (xy 344.268806 -60.114434) (xy 344.268806 -59.733434) (xy 344.776806 -59.733434)
				)
			)
		)
	)
	(footprint ""
		(layer "B.Cu")
		(at 453.8472 -131.8514 -90)
		(property "Reference" "R1M19"
			(at 0 0 90)
			(layer "B.SilkS")
			(hide yes)
			(effects
				(font
					(size 1.27 1.27)
				)
				(justify mirror)
			)
		)
		(property "Value" ""
			(at 0 0 90)
			(layer "B.Fab")
			(effects
				(font
					(size 1.27 1.27)
				)
				(justify mirror)
			)
		)
		(duplicate_pad_numbers_are_jumpers no)
		(fp_poly
			(pts
				(xy 0.2794 -0.1016) (xy -0.2794 -0.1016) (xy -0.2794 0.9906) (xy 0.2794 0.9906)
			)
			(stroke
				(width 0)
				(type default)
			)
			(fill no)
			(layer "B.CrtYd")
		)
		(fp_line
			(start -0.2794 0.9906)
			(end -0.2794 -0.1016)
			(stroke
				(width 0.1)
				(type default)
			)
			(layer "B.Fab")
		)
		(fp_line
			(start 0.2794 0.9906)
			(end -0.2794 0.9906)
			(stroke
				(width 0.1)
				(type default)
			)
			(layer "B.Fab")
		)
		(fp_line
			(start -0.2794 -0.1016)
			(end 0.2794 -0.1016)
			(stroke
				(width 0.1)
				(type default)
			)
			(layer "B.Fab")
		)
		(fp_line
			(start 0.2794 -0.1016)
			(end 0.2794 0.9906)
			(stroke
				(width 0.1)
				(type default)
			)
			(layer "B.Fab")
		)
		(pad "1" smd rect
			(at 0 0 90)
			(size 0.508 0.508)
			(layers "B.Cu" "B.Mask" "B.Paste")
			(net "P1V8_MCP_CPU0")
		)
		(pad "2" smd rect
			(at 0 0.889 90)
			(size 0.508 0.508)
			(layers "B.Cu" "B.Mask" "B.Paste")
			(net "JTAG_MCP_TMS")
		)
		(zone
			(layer "B.Cu")
			(hatch none 0.5)
			(connect_pads
				(clearance 0)
			)
			(min_thickness 0.25)
			(keepout
				(tracks not_allowed)
				(vias allowed)
				(pads allowed)
				(copperpour not_allowed)
				(footprints allowed)
			)
			(placement
				(enabled no)
				(sheetname "")
			)
			(fill
				(thermal_gap 0.5)
				(thermal_bridge_width 0.5)
				(island_removal_mode 0)
			)
			(polygon
				(pts
					(xy 453.2122 -131.5974) (xy 453.2122 -132.1054) (xy 453.5932 -132.1054) (xy 453.5932 -131.5974)
				)
			)
		)
		(zone
			(layer "B.Cu")
			(hatch none 0.5)
			(connect_pads
				(clearance 0)
			)
			(min_thickness 0.25)
			(keepout
				(tracks allowed)
				(vias not_allowed)
				(pads allowed)
				(copperpour not_allowed)
				(footprints allowed)
			)
			(placement
				(enabled no)
				(sheetname "")
			)
			(fill
				(thermal_gap 0.5)
				(thermal_bridge_width 0.5)
				(island_removal_mode 0)
			)
			(polygon
				(pts
					(xy 453.5932 -131.5974) (xy 453.5932 -132.1054) (xy 453.2122 -132.1054) (xy 453.2122 -131.5974)
				)
			)
		)
	)
	(footprint ""
		(layer "B.Cu")
		(at 32.832802 -92.485464 90)
		(property "Reference" "C9N25"
			(at 0 0 90)
			(layer "B.SilkS")
			(hide yes)
			(effects
				(font
					(size 1.27 1.27)
				)
				(justify mirror)
			)
		)
		(property "Value" ""
			(at 0 0 90)
			(layer "B.Fab")
			(effects
				(font
					(size 1.27 1.27)
				)
				(justify mirror)
			)
		)
		(duplicate_pad_numbers_are_jumpers no)
		(fp_poly
			(pts
				(xy 0.7239 -0.2159) (xy -0.7239 -0.2159) (xy -0.7239 1.9939) (xy 0.7239 1.9939)
			)
			(stroke
				(width 0)
				(type default)
			)
			(fill no)
			(layer "B.CrtYd")
		)
		(fp_line
			(start 0.7239 -0.2159)
			(end 0.7239 1.9939)
			(stroke
				(width 0.1)
				(type default)
			)
			(layer "B.Fab")
		)
		(fp_line
			(start -0.7239 -0.2159)
			(end 0.7239 -0.2159)
			(stroke
				(width 0.1)
				(type default)
			)
			(layer "B.Fab")
		)
		(fp_line
			(start 0.7239 1.9939)
			(end -0.7239 1.9939)
			(stroke
				(width 0.1)
				(type default)
			)
			(layer "B.Fab")
		)
		(fp_line
			(start -0.7239 1.9939)
			(end -0.7239 -0.2159)
			(stroke
				(width 0.1)
				(type default)
			)
			(layer "B.Fab")
		)
		(pad "1" smd rect
			(at 0 0 270)
			(size 1.27 1.016)
			(layers "B.Cu" "B.Mask" "B.Paste")
			(net "VR_FET_SW_P12V_STBY_PVCCIN_CPU1")
		)
		(pad "2" smd rect
			(at 0 1.778 270)
			(size 1.27 1.016)
			(layers "B.Cu" "B.Mask" "B.Paste")
			(net "GND")
		)
		(zone
			(layer "B.Cu")
			(hatch none 0.5)
			(connect_pads
				(clearance 0)
			)
			(min_thickness 0.25)
			(keepout
				(tracks not_allowed)
				(vias allowed)
				(pads allowed)
				(copperpour not_allowed)
				(footprints allowed)
			)
			(placement
				(enabled no)
				(sheetname "")
			)
			(fill
				(thermal_gap 0.5)
				(thermal_bridge_width 0.5)
				(island_removal_mode 0)
			)
			(polygon
				(pts
					(xy 33.340802 -93.120464) (xy 33.340802 -91.850464) (xy 34.102802 -91.850464) (xy 34.102802 -93.120464)
				)
			)
		)
	)
	(footprint ""
		(layer "B.Cu")
		(at 418.680646 -45.539152)
		(property "Reference" "R25W98"
			(at 0.8382 -0.67818 0)
			(unlocked yes)
			(layer "B.SilkS")
			(effects
				(font
					(size 0.4064 0.254)
					(thickness 0.1524)
				)
				(justify left mirror)
			)
		)
		(property "Value" ""
			(at 0 0 0)
			(layer "B.Fab")
			(effects
				(font
					(size 1.27 1.27)
				)
				(justify mirror)
			)
		)
		(duplicate_pad_numbers_are_jumpers no)
		(fp_poly
			(pts
				(xy 0.2794 -0.1016) (xy -0.2794 -0.1016) (xy -0.2794 0.9906) (xy 0.2794 0.9906)
			)
			(stroke
				(width 0)
				(type default)
			)
			(fill no)
			(layer "B.CrtYd")
		)
		(fp_line
			(start -0.2794 -0.1016)
			(end 0.2794 -0.1016)
			(stroke
				(width 0.1)
				(type default)
			)
			(layer "B.Fab")
		)
		(fp_line
			(start -0.2794 0.9906)
			(end -0.2794 -0.1016)
			(stroke
				(width 0.1)
				(type default)
			)
			(layer "B.Fab")
		)
		(fp_line
			(start 0.2794 -0.1016)
			(end 0.2794 0.9906)
			(stroke
				(width 0.1)
				(type default)
			)
			(layer "B.Fab")
		)
		(fp_line
			(start 0.2794 0.9906)
			(end -0.2794 0.9906)
			(stroke
				(width 0.1)
				(type default)
			)
			(layer "B.Fab")
		)
		(pad "1" smd rect
			(at 0 0 180)
			(size 0.508 0.508)
			(layers "B.Cu" "B.Mask" "B.Paste")
			(net "P3V3_STBY")
		)
		(pad "2" smd rect
			(at 0 0.889 180)
			(size 0.508 0.508)
			(layers "B.Cu" "B.Mask" "B.Paste")
			(net "BMC_STRAP_BIT3")
		)
		(zone
			(layer "B.Cu")
			(hatch none 0.5)
			(connect_pads
				(clearance 0)
			)
			(min_thickness 0.25)
			(keepout
				(tracks allowed)
				(vias not_allowed)
				(pads allowed)
				(copperpour not_allowed)
				(footprints allowed)
			)
			(placement
				(enabled no)
				(sheetname "")
			)
			(fill
				(thermal_gap 0.5)
				(thermal_bridge_width 0.5)
				(island_removal_mode 0)
			)
			(polygon
				(pts
					(xy 418.934646 -45.285152) (xy 418.426646 -45.285152) (xy 418.426646 -44.904152) (xy 418.934646 -44.904152)
				)
			)
		)
		(zone
			(layer "B.Cu")
			(hatch none 0.5)
			(connect_pads
				(clearance 0)
			)
			(min_thickness 0.25)
			(keepout
				(tracks not_allowed)
				(vias allowed)
				(pads allowed)
				(copperpour not_allowed)
				(footprints allowed)
			)
			(placement
				(enabled no)
				(sheetname "")
			)
			(fill
				(thermal_gap 0.5)
				(thermal_bridge_width 0.5)
				(island_removal_mode 0)
			)
			(polygon
				(pts
					(xy 418.934646 -44.904152) (xy 418.426646 -44.904152) (xy 418.426646 -45.285152) (xy 418.934646 -45.285152)
				)
			)
		)
	)
	(footprint ""
		(layer "B.Cu")
		(at 184.0484 -132.842 90)
		(property "Reference" "C22W5"
			(at 0 0 90)
			(layer "B.SilkS")
			(hide yes)
			(effects
				(font
					(size 1.27 1.27)
				)
				(justify mirror)
			)
		)
		(property "Value" "*"
			(at 0.0762 -6.2357 90)
			(unlocked yes)
			(layer "B.Fab")
			(hide yes)
			(effects
				(font
					(size 1.27 1.016)
					(thickness 0.1524)
				)
				(justify mirror)
			)
		)
		(property "Device Type" "SC22U16V5MX-4-GP_SMD-BCG5-SC22A"
			(at 0.0762 -8.2677 90)
			(unlocked yes)
			(layer "B.Fab")
			(hide yes)
			(effects
				(font
					(size 1.27 1.016)
					(thickness 0.1524)
				)
				(justify mirror)
			)
		)
		(duplicate_pad_numbers_are_jumpers no)
		(fp_line
			(start -0.635 0)
			(end 0.635 0)
			(stroke
				(width 0.508)
				(type default)
			)
			(layer "B.SilkS")
		)
		(fp_rect
			(start 0.9652 1.778)
			(end -0.9652 -1.778)
			(stroke
				(width 0)
				(type default)
			)
			(fill no)
			(layer "B.CrtYd")
		)
		(fp_poly
			(pts
				(xy 0.9652 -1.778) (xy -0.9652 -1.778) (xy -0.9652 1.778) (xy 0.9652 1.778)
			)
			(stroke
				(width 0)
				(type default)
			)
			(fill no)
			(layer "B.Fab")
		)
		(pad "1" smd rect
			(at 0 -0.9652 270)
			(size 1.397 1.143)
			(layers "B.Cu" "B.Mask" "B.Paste")
			(net "VR_FET_SW_P12V_STBY_PVPP_KLM")
		)
		(pad "2" smd rect
			(at 0 0.9652 270)
			(size 1.397 1.143)
			(layers "B.Cu" "B.Mask" "B.Paste")
			(net "GND")
		)
	)
	(footprint ""
		(layer "B.Cu")
		(at 16.4084 -87.1601 -90)
		(property "Reference" "R9P4"
			(at 0 0 90)
			(layer "B.SilkS")
			(hide yes)
			(effects
				(font
					(size 1.27 1.27)
				)
				(justify mirror)
			)
		)
		(property "Value" ""
			(at 0 0 90)
			(layer "B.Fab")
			(effects
				(font
					(size 1.27 1.27)
				)
				(justify mirror)
			)
		)
		(duplicate_pad_numbers_are_jumpers no)
		(fp_poly
			(pts
				(xy 0.2794 -0.1016) (xy -0.2794 -0.1016) (xy -0.2794 0.9906) (xy 0.2794 0.9906)
			)
			(stroke
				(width 0)
				(type default)
			)
			(fill no)
			(layer "B.CrtYd")
		)
		(fp_line
			(start -0.2794 0.9906)
			(end -0.2794 -0.1016)
			(stroke
				(width 0.1)
				(type default)
			)
			(layer "B.Fab")
		)
		(fp_line
			(start 0.2794 0.9906)
			(end -0.2794 0.9906)
			(stroke
				(width 0.1)
				(type default)
			)
			(layer "B.Fab")
		)
		(fp_line
			(start -0.2794 -0.1016)
			(end 0.2794 -0.1016)
			(stroke
				(width 0.1)
				(type default)
			)
			(layer "B.Fab")
		)
		(fp_line
			(start 0.2794 -0.1016)
			(end 0.2794 0.9906)
			(stroke
				(width 0.1)
				(type default)
			)
			(layer "B.Fab")
		)
		(pad "1" smd rect
			(at 0 0 90)
			(size 0.508 0.508)
			(layers "B.Cu" "B.Mask" "B.Paste")
			(net "P3V3_STBY")
		)
		(pad "2" smd rect
			(at 0 0.889 90)
			(size 0.508 0.508)
			(layers "B.Cu" "B.Mask" "B.Paste")
			(net "IRQ_UV_DETECT_N")
		)
		(zone
			(layer "B.Cu")
			(hatch none 0.5)
			(connect_pads
				(clearance 0)
			)
			(min_thickness 0.25)
			(keepout
				(tracks not_allowed)
				(vias allowed)
				(pads allowed)
				(copperpour not_allowed)
				(footprints allowed)
			)
			(placement
				(enabled no)
				(sheetname "")
			)
			(fill
				(thermal_gap 0.5)
				(thermal_bridge_width 0.5)
				(island_removal_mode 0)
			)
			(polygon
				(pts
					(xy 15.7734 -86.9061) (xy 15.7734 -87.4141) (xy 16.1544 -87.4141) (xy 16.1544 -86.9061)
				)
			)
		)
		(zone
			(layer "B.Cu")
			(hatch none 0.5)
			(connect_pads
				(clearance 0)
			)
			(min_thickness 0.25)
			(keepout
				(tracks allowed)
				(vias not_allowed)
				(pads allowed)
				(copperpour not_allowed)
				(footprints allowed)
			)
			(placement
				(enabled no)
				(sheetname "")
			)
			(fill
				(thermal_gap 0.5)
				(thermal_bridge_width 0.5)
				(island_removal_mode 0)
			)
			(polygon
				(pts
					(xy 16.1544 -86.9061) (xy 16.1544 -87.4141) (xy 15.7734 -87.4141) (xy 15.7734 -86.9061)
				)
			)
		)
	)
	(footprint ""
		(layer "B.Cu")
		(at 17.83842 -100.60432 90)
		(property "Reference" "C9N12"
			(at 0 0 90)
			(layer "B.SilkS")
			(hide yes)
			(effects
				(font
					(size 1.27 1.27)
				)
				(justify mirror)
			)
		)
		(property "Value" ""
			(at 0 0 90)
			(layer "B.Fab")
			(effects
				(font
					(size 1.27 1.27)
				)
				(justify mirror)
			)
		)
		(duplicate_pad_numbers_are_jumpers no)
		(fp_poly
			(pts
				(xy -0.3048 -0.1016) (xy -0.3048 0.9906) (xy 0.3048 0.9906) (xy 0.3048 -0.1016)
			)
			(stroke
				(width 0)
				(type default)
			)
			(fill no)
			(layer "B.CrtYd")
		)
		(fp_line
			(start 0.3048 -0.1016)
			(end 0.3048 0.9906)
			(stroke
				(width 0.1)
				(type default)
			)
			(layer "B.Fab")
		)
		(fp_line
			(start -0.3048 -0.1016)
			(end 0.3048 -0.1016)
			(stroke
				(width 0.1)
				(type default)
			)
			(layer "B.Fab")
		)
		(fp_line
			(start 0.3048 0.9906)
			(end -0.3048 0.9906)
			(stroke
				(width 0.1)
				(type default)
			)
			(layer "B.Fab")
		)
		(fp_line
			(start -0.3048 0.9906)
			(end -0.3048 -0.1016)
			(stroke
				(width 0.1)
				(type default)
			)
			(layer "B.Fab")
		)
		(pad "1" smd rect
			(at 0 0 270)
			(size 0.508 0.508)
			(layers "B.Cu" "B.Mask" "B.Paste")
			(net "P3E_CPU1_PE3_MP_C_TXP<9>")
		)
		(pad "2" smd rect
			(at 0 0.889 270)
			(size 0.508 0.508)
			(layers "B.Cu" "B.Mask" "B.Paste")
			(net "P3E_CPU1_PE3_MP_TXP<9>")
		)
		(zone
			(layer "B.Cu")
			(hatch none 0.5)
			(connect_pads
				(clearance 0)
			)
			(min_thickness 0.25)
			(keepout
				(tracks allowed)
				(vias not_allowed)
				(pads allowed)
				(copperpour not_allowed)
				(footprints allowed)
			)
			(placement
				(enabled no)
				(sheetname "")
			)
			(fill
				(thermal_gap 0.5)
				(thermal_bridge_width 0.5)
				(island_removal_mode 0)
			)
			(polygon
				(pts
					(xy 18.09242 -100.85832) (xy 18.09242 -100.35032) (xy 18.47342 -100.35032) (xy 18.47342 -100.85832)
				)
			)
		)
		(zone
			(layer "B.Cu")
			(hatch none 0.5)
			(connect_pads
				(clearance 0)
			)
			(min_thickness 0.25)
			(keepout
				(tracks not_allowed)
				(vias allowed)
				(pads allowed)
				(copperpour not_allowed)
				(footprints allowed)
			)
			(placement
				(enabled no)
				(sheetname "")
			)
			(fill
				(thermal_gap 0.5)
				(thermal_bridge_width 0.5)
				(island_removal_mode 0)
			)
			(polygon
				(pts
					(xy 18.47342 -100.85832) (xy 18.47342 -100.35032) (xy 18.09242 -100.35032) (xy 18.09242 -100.85832)
				)
			)
		)
	)
	(footprint ""
		(layer "B.Cu")
		(at 30.554168 -135.3312 90)
		(property "Reference" "C9M1"
			(at 0 0 90)
			(layer "B.SilkS")
			(hide yes)
			(effects
				(font
					(size 1.27 1.27)
				)
				(justify mirror)
			)
		)
		(property "Value" ""
			(at 0 0 90)
			(layer "B.Fab")
			(effects
				(font
					(size 1.27 1.27)
				)
				(justify mirror)
			)
		)
		(duplicate_pad_numbers_are_jumpers no)
		(fp_poly
			(pts
				(xy -0.3048 -0.1016) (xy -0.3048 0.9906) (xy 0.3048 0.9906) (xy 0.3048 -0.1016)
			)
			(stroke
				(width 0)
				(type default)
			)
			(fill no)
			(layer "B.CrtYd")
		)
		(fp_line
			(start 0.3048 -0.1016)
			(end 0.3048 0.9906)
			(stroke
				(width 0.1)
				(type default)
			)
			(layer "B.Fab")
		)
		(fp_line
			(start -0.3048 -0.1016)
			(end 0.3048 -0.1016)
			(stroke
				(width 0.1)
				(type default)
			)
			(layer "B.Fab")
		)
		(fp_line
			(start 0.3048 0.9906)
			(end -0.3048 0.9906)
			(stroke
				(width 0.1)
				(type default)
			)
			(layer "B.Fab")
		)
		(fp_line
			(start -0.3048 0.9906)
			(end -0.3048 -0.1016)
			(stroke
				(width 0.1)
				(type default)
			)
			(layer "B.Fab")
		)
		(pad "1" smd rect
			(at 0 0 270)
			(size 0.508 0.508)
			(layers "B.Cu" "B.Mask" "B.Paste")
			(net "M_K_VREF")
		)
		(pad "2" smd rect
			(at 0 0.889 270)
			(size 0.508 0.508)
			(layers "B.Cu" "B.Mask" "B.Paste")
			(net "GND")
		)
		(zone
			(layer "B.Cu")
			(hatch none 0.5)
			(connect_pads
				(clearance 0)
			)
			(min_thickness 0.25)
			(keepout
				(tracks allowed)
				(vias not_allowed)
				(pads allowed)
				(copperpour not_allowed)
				(footprints allowed)
			)
			(placement
				(enabled no)
				(sheetname "")
			)
			(fill
				(thermal_gap 0.5)
				(thermal_bridge_width 0.5)
				(island_removal_mode 0)
			)
			(polygon
				(pts
					(xy 30.808168 -135.5852) (xy 30.808168 -135.0772) (xy 31.189168 -135.0772) (xy 31.189168 -135.5852)
				)
			)
		)
		(zone
			(layer "B.Cu")
			(hatch none 0.5)
			(connect_pads
				(clearance 0)
			)
			(min_thickness 0.25)
			(keepout
				(tracks not_allowed)
				(vias allowed)
				(pads allowed)
				(copperpour not_allowed)
				(footprints allowed)
			)
			(placement
				(enabled no)
				(sheetname "")
			)
			(fill
				(thermal_gap 0.5)
				(thermal_bridge_width 0.5)
				(island_removal_mode 0)
			)
			(polygon
				(pts
					(xy 31.189168 -135.5852) (xy 31.189168 -135.0772) (xy 30.808168 -135.0772) (xy 30.808168 -135.5852)
				)
			)
		)
	)
)
